(kicad_pcb
	(version 20260206)
	(generator "pcbnew")
	(generator_version "10.0")
	(general
		(thickness 1.6)
		(legacy_teardrops no)
	)
	(paper "A4")
	(title_block
		(title "04192023_DAF0TMB3IC0_F0TG_MB_C_brd_V02_OCP.brd")
		(comment 1 "Grand Teton / footprints 226-229 of 8354")
	)
	(layers
		(0 "F.Cu" signal "TOP")
		(4 "In1.Cu" signal "GND")
		(6 "In2.Cu" signal "IN1")
		(8 "In3.Cu" signal "GND1")
		(10 "In4.Cu" signal "IN2")
		(12 "In5.Cu" signal "GND2")
		(14 "In6.Cu" signal "IN3")
		(16 "In7.Cu" signal "GND3")
		(18 "In8.Cu" signal "VCC")
		(20 "In9.Cu" signal "VCC1")
		(22 "In10.Cu" signal "GND4")
		(24 "In11.Cu" signal "IN4")
		(26 "In12.Cu" signal "GND5")
		(28 "In13.Cu" signal "IN5")
		(30 "In14.Cu" signal "GND6")
		(32 "In15.Cu" signal "IN6")
		(34 "In16.Cu" signal "GND7")
		(2 "B.Cu" signal "BOTTOM")
		(9 "F.Adhes" user "F.Adhesive")
		(11 "B.Adhes" user "B.Adhesive")
		(13 "F.Paste" user "Package Geometry/Pastemask Top")
		(15 "B.Paste" user "Package Geometry/Pastemask Bottom")
		(5 "F.SilkS" user "Ref Des/Silkscreen Top")
		(7 "B.SilkS" user "Ref Des/Silkscreen Bottom")
		(1 "F.Mask" user "Board Geometry/Soldermask Top")
		(3 "B.Mask" user "Board Geometry/Soldermask Bottom")
		(17 "Dwgs.User" user "User.Drawings")
		(19 "Cmts.User" user "User.Comments")
		(21 "Eco1.User" user "User.Eco1")
		(23 "Eco2.User" user "User.Eco2")
		(25 "Edge.Cuts" user "Board Geometry/Outline")
		(27 "Margin" user)
		(31 "F.CrtYd" user "Package Geometry/Place Bound Top")
		(29 "B.CrtYd" user "Package Geometry/Place Bound Bottom")
		(35 "F.Fab" user "Ref Des/Assembly Top")
		(33 "B.Fab" user "Ref Des/Assembly Bottom")
	)
	(footprint ""
		(layer "F.Cu")
		(at 445.19088 -94.602808)
		(property "Reference" "R3563"
			(at 0 0 0)
			(layer "F.SilkS")
			(hide yes)
			(effects
				(font
					(size 1.27 1.27)
				)
			)
		)
		(property "Value" ""
			(at 0 0 0)
			(layer "F.Fab")
			(effects
				(font
					(size 1.27 1.27)
				)
			)
		)
		(duplicate_pad_numbers_are_jumpers no)
		(fp_line
			(start -0.7874 -0.4064)
			(end 0.7874 -0.4064)
			(stroke
				(width 0.1524)
				(type default)
			)
			(layer "F.SilkS")
		)
		(fp_line
			(start -0.7874 0.4064)
			(end -0.7874 -0.4064)
			(stroke
				(width 0.1524)
				(type default)
			)
			(layer "F.SilkS")
		)
		(fp_line
			(start 0.7874 -0.4064)
			(end 0.7874 0.4064)
			(stroke
				(width 0.1524)
				(type default)
			)
			(layer "F.SilkS")
		)
		(fp_line
			(start 0.7874 0.4064)
			(end -0.7874 0.4064)
			(stroke
				(width 0.1524)
				(type default)
			)
			(layer "F.SilkS")
		)
		(fp_line
			(start -0.67945 -0.305054)
			(end -0.12065 -0.305054)
			(stroke
				(width 0.1)
				(type default)
			)
			(layer "F.Fab")
		)
		(fp_line
			(start -0.67945 0.3048)
			(end -0.67945 -0.305054)
			(stroke
				(width 0.1)
				(type default)
			)
			(layer "F.Fab")
		)
		(fp_line
			(start -0.12065 -0.305054)
			(end -0.12065 -0.2794)
			(stroke
				(width 0.1)
				(type default)
			)
			(layer "F.Fab")
		)
		(fp_line
			(start -0.12065 -0.2794)
			(end 0.12065 -0.2794)
			(stroke
				(width 0.1)
				(type default)
			)
			(layer "F.Fab")
		)
		(fp_line
			(start -0.12065 0.2794)
			(end -0.12065 0.3048)
			(stroke
				(width 0.1)
				(type default)
			)
			(layer "F.Fab")
		)
		(fp_line
			(start -0.12065 0.3048)
			(end -0.67945 0.3048)
			(stroke
				(width 0.1)
				(type default)
			)
			(layer "F.Fab")
		)
		(fp_line
			(start 0.120396 0.2794)
			(end -0.12065 0.2794)
			(stroke
				(width 0.1)
				(type default)
			)
			(layer "F.Fab")
		)
		(fp_line
			(start 0.120396 0.3048)
			(end 0.120396 0.2794)
			(stroke
				(width 0.1)
				(type default)
			)
			(layer "F.Fab")
		)
		(fp_line
			(start 0.12065 -0.3048)
			(end 0.67945 -0.3048)
			(stroke
				(width 0.1)
				(type default)
			)
			(layer "F.Fab")
		)
		(fp_line
			(start 0.12065 -0.2794)
			(end 0.12065 -0.3048)
			(stroke
				(width 0.1)
				(type default)
			)
			(layer "F.Fab")
		)
		(fp_line
			(start 0.67945 -0.3048)
			(end 0.67945 0.3048)
			(stroke
				(width 0.1)
				(type default)
			)
			(layer "F.Fab")
		)
		(fp_line
			(start 0.67945 0.3048)
			(end 0.120396 0.3048)
			(stroke
				(width 0.1)
				(type default)
			)
			(layer "F.Fab")
		)
		(pad "1" smd circle
			(at -0.40005 0)
			(size 0 0)
			(layers "F.Cu" "F.Mask" "F.Paste")
			(net "OCP_SFF_P3V3_ADC_ALERT_R")
		)
		(pad "2" smd circle
			(at 0.40005 0)
			(size 0 0)
			(layers "F.Cu" "F.Mask" "F.Paste")
			(net "OCP_SFF_P3V3_P12V_ADC_R_ALERT")
		)
	)
	(footprint ""
		(layer "F.Cu")
		(at 269.85087 -351.540572 90)
		(property "Reference" "PR442"
			(at 0 0 90)
			(layer "F.SilkS")
			(hide yes)
			(effects
				(font
					(size 1.27 1.27)
				)
			)
		)
		(property "Value" ""
			(at 0 0 90)
			(layer "F.Fab")
			(effects
				(font
					(size 1.27 1.27)
				)
			)
		)
		(duplicate_pad_numbers_are_jumpers no)
		(fp_line
			(start 0.7874 -0.4064)
			(end 0.7874 0.4064)
			(stroke
				(width 0.1524)
				(type default)
			)
			(layer "F.SilkS")
		)
		(fp_line
			(start -0.7874 -0.4064)
			(end 0.7874 -0.4064)
			(stroke
				(width 0.1524)
				(type default)
			)
			(layer "F.SilkS")
		)
		(fp_line
			(start 0.7874 0.4064)
			(end -0.7874 0.4064)
			(stroke
				(width 0.1524)
				(type default)
			)
			(layer "F.SilkS")
		)
		(fp_line
			(start -0.7874 0.4064)
			(end -0.7874 -0.4064)
			(stroke
				(width 0.1524)
				(type default)
			)
			(layer "F.SilkS")
		)
		(fp_line
			(start -0.12065 -0.305054)
			(end -0.12065 -0.2794)
			(stroke
				(width 0.1)
				(type default)
			)
			(layer "F.Fab")
		)
		(fp_line
			(start -0.67945 -0.305054)
			(end -0.12065 -0.305054)
			(stroke
				(width 0.1)
				(type default)
			)
			(layer "F.Fab")
		)
		(fp_line
			(start 0.67945 -0.3048)
			(end 0.67945 0.3048)
			(stroke
				(width 0.1)
				(type default)
			)
			(layer "F.Fab")
		)
		(fp_line
			(start 0.12065 -0.3048)
			(end 0.67945 -0.3048)
			(stroke
				(width 0.1)
				(type default)
			)
			(layer "F.Fab")
		)
		(fp_line
			(start 0.12065 -0.2794)
			(end 0.12065 -0.3048)
			(stroke
				(width 0.1)
				(type default)
			)
			(layer "F.Fab")
		)
		(fp_line
			(start -0.12065 -0.2794)
			(end 0.12065 -0.2794)
			(stroke
				(width 0.1)
				(type default)
			)
			(layer "F.Fab")
		)
		(fp_line
			(start 0.120396 0.2794)
			(end -0.12065 0.2794)
			(stroke
				(width 0.1)
				(type default)
			)
			(layer "F.Fab")
		)
		(fp_line
			(start -0.12065 0.2794)
			(end -0.12065 0.3048)
			(stroke
				(width 0.1)
				(type default)
			)
			(layer "F.Fab")
		)
		(fp_line
			(start 0.67945 0.3048)
			(end 0.120396 0.3048)
			(stroke
				(width 0.1)
				(type default)
			)
			(layer "F.Fab")
		)
		(fp_line
			(start 0.120396 0.3048)
			(end 0.120396 0.2794)
			(stroke
				(width 0.1)
				(type default)
			)
			(layer "F.Fab")
		)
		(fp_line
			(start -0.12065 0.3048)
			(end -0.67945 0.3048)
			(stroke
				(width 0.1)
				(type default)
			)
			(layer "F.Fab")
		)
		(fp_line
			(start -0.67945 0.3048)
			(end -0.67945 -0.305054)
			(stroke
				(width 0.1)
				(type default)
			)
			(layer "F.Fab")
		)
		(pad "1" smd circle
			(at -0.40005 0 90)
			(size 0 0)
			(layers "F.Cu" "F.Mask" "F.Paste")
			(net "PVDDCR_CPU1_P0_PVCC")
		)
		(pad "2" smd circle
			(at 0.40005 0 90)
			(size 0 0)
			(layers "F.Cu" "F.Mask" "F.Paste")
			(net "P5V_AUX")
		)
	)
	(footprint ""
		(layer "F.Cu")
		(at 116.314474 -55.036212 -90)
		(property "Reference" "R1729"
			(at 0 0 270)
			(layer "F.SilkS")
			(hide yes)
			(effects
				(font
					(size 1.27 1.27)
				)
			)
		)
		(property "Value" ""
			(at 0 0 270)
			(layer "F.Fab")
			(effects
				(font
					(size 1.27 1.27)
				)
			)
		)
		(duplicate_pad_numbers_are_jumpers no)
		(fp_line
			(start -0.7874 0.4064)
			(end -0.7874 -0.4064)
			(stroke
				(width 0.1524)
				(type default)
			)
			(layer "F.SilkS")
		)
		(fp_line
			(start 0.7874 0.4064)
			(end -0.7874 0.4064)
			(stroke
				(width 0.1524)
				(type default)
			)
			(layer "F.SilkS")
		)
		(fp_line
			(start -0.7874 -0.4064)
			(end 0.7874 -0.4064)
			(stroke
				(width 0.1524)
				(type default)
			)
			(layer "F.SilkS")
		)
		(fp_line
			(start 0.7874 -0.4064)
			(end 0.7874 0.4064)
			(stroke
				(width 0.1524)
				(type default)
			)
			(layer "F.SilkS")
		)
		(fp_line
			(start -0.67945 0.3048)
			(end -0.67945 -0.305054)
			(stroke
				(width 0.1)
				(type default)
			)
			(layer "F.Fab")
		)
		(fp_line
			(start -0.12065 0.3048)
			(end -0.67945 0.3048)
			(stroke
				(width 0.1)
				(type default)
			)
			(layer "F.Fab")
		)
		(fp_line
			(start 0.120396 0.3048)
			(end 0.120396 0.2794)
			(stroke
				(width 0.1)
				(type default)
			)
			(layer "F.Fab")
		)
		(fp_line
			(start 0.67945 0.3048)
			(end 0.120396 0.3048)
			(stroke
				(width 0.1)
				(type default)
			)
			(layer "F.Fab")
		)
		(fp_line
			(start -0.12065 0.2794)
			(end -0.12065 0.3048)
			(stroke
				(width 0.1)
				(type default)
			)
			(layer "F.Fab")
		)
		(fp_line
			(start 0.120396 0.2794)
			(end -0.12065 0.2794)
			(stroke
				(width 0.1)
				(type default)
			)
			(layer "F.Fab")
		)
		(fp_line
			(start -0.12065 -0.2794)
			(end 0.12065 -0.2794)
			(stroke
				(width 0.1)
				(type default)
			)
			(layer "F.Fab")
		)
		(fp_line
			(start 0.12065 -0.2794)
			(end 0.12065 -0.3048)
			(stroke
				(width 0.1)
				(type default)
			)
			(layer "F.Fab")
		)
		(fp_line
			(start 0.12065 -0.3048)
			(end 0.67945 -0.3048)
			(stroke
				(width 0.1)
				(type default)
			)
			(layer "F.Fab")
		)
		(fp_line
			(start 0.67945 -0.3048)
			(end 0.67945 0.3048)
			(stroke
				(width 0.1)
				(type default)
			)
			(layer "F.Fab")
		)
		(fp_line
			(start -0.67945 -0.305054)
			(end -0.12065 -0.305054)
			(stroke
				(width 0.1)
				(type default)
			)
			(layer "F.Fab")
		)
		(fp_line
			(start -0.12065 -0.305054)
			(end -0.12065 -0.2794)
			(stroke
				(width 0.1)
				(type default)
			)
			(layer "F.Fab")
		)
		(pad "1" smd circle
			(at -0.40005 0 270)
			(size 0 0)
			(layers "F.Cu" "F.Mask" "F.Paste")
			(net "SCM_JTAG_MUX_S1")
		)
		(pad "2" smd circle
			(at 0.40005 0 270)
			(size 0 0)
			(layers "F.Cu" "F.Mask" "F.Paste")
			(net "GND")
		)
	)
	(footprint ""
		(layer "F.Cu")
		(at 29.478478 -17.623536 90)
		(property "Reference" "C688"
			(at 0 0 90)
			(layer "F.SilkS")
			(hide yes)
			(effects
				(font
					(size 1.27 1.27)
				)
			)
		)
		(property "Value" ""
			(at 0 0 90)
			(layer "F.Fab")
			(effects
				(font
					(size 1.27 1.27)
				)
			)
		)
		(duplicate_pad_numbers_are_jumpers no)
		(fp_line
			(start 0.299974 -0.150114)
			(end 0.299974 0.150114)
			(stroke
				(width 0.1)
				(type default)
			)
			(layer "F.Fab")
		)
		(fp_line
			(start -0.299974 -0.150114)
			(end 0.299974 -0.150114)
			(stroke
				(width 0.1)
				(type default)
			)
			(layer "F.Fab")
		)
		(fp_line
			(start 0.299974 0.150114)
			(end -0.299974 0.150114)
			(stroke
				(width 0.1)
				(type default)
			)
			(layer "F.Fab")
		)
		(fp_line
			(start -0.299974 0.150114)
			(end -0.299974 -0.150114)
			(stroke
				(width 0.1)
				(type default)
			)
			(layer "F.Fab")
		)
		(pad "1" smd rect
			(at -0.2667 0 90)
			(size 0.3048 0.381)
			(layers "F.Cu" "F.Mask" "F.Paste")
			(net "P5E_CPU1_G1_TX_C_DN<10>")
		)
		(pad "2" smd rect
			(at 0.2667 0 90)
			(size 0.3048 0.381)
			(layers "F.Cu" "F.Mask" "F.Paste")
			(net "P5E_CPU1_G1_TX_DN<10>")
		)
	)
)
